(kicad_pcb
	(version 20241229)
	(generator "pcbnew")
	(generator_version "9.0")
	(general
		(thickness 1.599998)
		(legacy_teardrops no)
	)
	(paper "A4")
	(title_block
		(title "Artix - Datacenter Secure Control Module (DC-SCM)")
		(date "2024-11-06")
		(rev "1.1.3")
		(comment 9 "footprint 134 of 544 (U1), pads 1-85 of 100")
	)
	(layers
		(0 "F.Cu" signal)
		(4 "In1.Cu" signal)
		(6 "In2.Cu" signal)
		(8 "In3.Cu" signal)
		(10 "In4.Cu" signal)
		(12 "In5.Cu" signal)
		(14 "In6.Cu" signal)
		(2 "B.Cu" signal)
		(9 "F.Adhes" user "F.Adhesive")
		(11 "B.Adhes" user "B.Adhesive")
		(13 "F.Paste" user)
		(15 "B.Paste" user)
		(5 "F.SilkS" user "F.Silkscreen")
		(7 "B.SilkS" user "B.Silkscreen")
		(1 "F.Mask" user)
		(3 "B.Mask" user)
		(17 "Dwgs.User" user "User.Drawings")
		(19 "Cmts.User" user "User.Comments")
		(21 "Eco1.User" user "User.Eco1")
		(23 "Eco2.User" user "User.Eco2")
		(25 "Edge.Cuts" user)
		(27 "Margin" user)
		(31 "F.CrtYd" user "F.Courtyard")
		(29 "B.CrtYd" user "B.Courtyard")
		(35 "F.Fab" user)
		(33 "B.Fab" user)
	)
	(footprint "antmicro-footprints:BGA-170-100_18x14mm_Layout17x10_P1mm"
		(layer "F.Cu")
		(at 138.774 125.014 180)
		(descr "Uses depopulated JEDEC-MO-304B")
		(property "Reference" "U1"
			(at 6.974 9.314 180)
			(layer "F.SilkS")
			(effects
				(font
					(size 0.7 0.7)
					(thickness 0.15)
				)
				(justify left bottom)
			)
		)
		(property "Value" "MTFC16GAPALNA-AIT"
			(at 16.305 13.334 180)
			(layer "F.Fab")
			(effects
				(font
					(size 0.7 0.7)
					(thickness 0.15)
				)
				(justify left bottom)
			)
		)
		(property "Datasheet" "https://www.mouser.com/datasheet/2/671/micron_technology_mict-s-a0006806196-1-1759129.pdf"
			(at 0 0 180)
			(layer "F.Fab")
			(hide yes)
			(effects
				(font
					(size 1.27 1.27)
					(thickness 0.15)
				)
			)
		)
		(property "Description" "Managed NAND Flash Serial e-MMC 3.3V 128G-bit 128G/32G/16G x 1/4-bit/8-bit Automotive AEC-Q100 100-Pin TBGA Tray"
			(at 0 0 180)
			(layer "F.Fab")
			(hide yes)
			(effects
				(font
					(size 1.27 1.27)
					(thickness 0.15)
				)
			)
		)
		(property "Author" "Antmicro"
			(at 277.548 250.028 0)
			(layer "F.Fab")
			(hide yes)
			(effects
				(font
					(size 1 1)
					(thickness 0.15)
				)
			)
		)
		(property "License" "Apache-2.0"
			(at 277.548 250.028 0)
			(layer "F.Fab")
			(hide yes)
			(effects
				(font
					(size 1 1)
					(thickness 0.15)
				)
			)
		)
		(property "MPN" "MTFC16GAPALNA-AIT"
			(at 277.548 250.028 0)
			(layer "F.Fab")
			(hide yes)
			(effects
				(font
					(size 1 1)
					(thickness 0.15)
				)
			)
		)
		(property "Manufacturer" "Micron Technology"
			(at 277.548 250.028 0)
			(layer "F.Fab")
			(hide yes)
			(effects
				(font
					(size 1 1)
					(thickness 0.15)
				)
			)
		)
		(sheetname "/Interfaces/")
		(sheetfile "interfaces.kicad_sch")
		(attr smd)
		(pad "A1" smd circle
			(at -4.5 -8 180)
			(size 0.37 0.37)
			(layers "F.Cu" "F.Mask" "F.Paste")
			(net 417 "unconnected-(U1-NC-PadA1)")
			(pinfunction "NC")
			(pintype "no_connect")
		)
		(pad "A2" smd circle
			(at -3.5 -8 180)
			(size 0.37 0.37)
			(layers "F.Cu" "F.Mask" "F.Paste")
			(net 418 "unconnected-(U1-NC-PadA2)")
			(pinfunction "NC")
			(pintype "no_connect")
		)
		(pad "A9" smd circle
			(at 3.499 -8 180)
			(size 0.37 0.37)
			(layers "F.Cu" "F.Mask" "F.Paste")
			(net 419 "unconnected-(U1-NC-PadA9)")
			(pinfunction "NC")
			(pintype "no_connect")
		)
		(pad "A10" smd circle
			(at 4.499 -8 180)
			(size 0.37 0.37)
			(layers "F.Cu" "F.Mask" "F.Paste")
			(net 426 "unconnected-(U1-NC-PadA10)")
			(pinfunction "NC")
			(pintype "no_connect")
		)
		(pad "B1" smd circle
			(at -4.5 -7 180)
			(size 0.37 0.37)
			(layers "F.Cu" "F.Mask" "F.Paste")
			(net 436 "unconnected-(U1-NC-PadB1)")
			(pinfunction "NC")
			(pintype "no_connect")
		)
		(pad "B10" smd circle
			(at 4.499 -7 180)
			(size 0.37 0.37)
			(layers "F.Cu" "F.Mask" "F.Paste")
			(net 437 "unconnected-(U1-NC-PadB10)")
			(pinfunction "NC")
			(pintype "no_connect")
		)
		(pad "D2" smd circle
			(at -3.5 -5 180)
			(size 0.37 0.37)
			(layers "F.Cu" "F.Mask" "F.Paste")
			(net 438 "unconnected-(U1-VSF1-PadD2)")
			(pinfunction "VSF1")
			(pintype "no_connect")
		)
		(pad "D3" smd circle
			(at -2.5 -5 180)
			(size 0.37 0.37)
			(layers "F.Cu" "F.Mask" "F.Paste")
			(net 439 "unconnected-(U1-VSF2-PadD3)")
			(pinfunction "VSF2")
			(pintype "no_connect")
		)
		(pad "D4" smd circle
			(at -1.5 -5 180)
			(size 0.37 0.37)
			(layers "F.Cu" "F.Mask" "F.Paste")
			(net 440 "unconnected-(U1-VSF3-PadD4)")
			(pinfunction "VSF3")
			(pintype "no_connect")
		)
		(pad "D5" smd circle
			(at -0.5 -5 180)
			(size 0.37 0.37)
			(layers "F.Cu" "F.Mask" "F.Paste")
			(net 441 "unconnected-(U1-VSF4-PadD5)")
			(pinfunction "VSF4")
			(pintype "no_connect")
		)
		(pad "D6" smd circle
			(at 0.499 -5 180)
			(size 0.37 0.37)
			(layers "F.Cu" "F.Mask" "F.Paste")
			(net 443 "unconnected-(U1-VSF5-PadD6)")
			(pinfunction "VSF5")
			(pintype "no_connect")
		)
		(pad "D7" smd circle
			(at 1.499 -5 180)
			(size 0.37 0.37)
			(layers "F.Cu" "F.Mask" "F.Paste")
			(net 456 "unconnected-(U1-VSF6-PadD7)")
			(pinfunction "VSF6")
			(pintype "no_connect")
		)
		(pad "D8" smd circle
			(at 2.499 -5 180)
			(size 0.37 0.37)
			(layers "F.Cu" "F.Mask" "F.Paste")
			(net 470 "unconnected-(U1-VSF7-PadD8)")
			(pinfunction "VSF7")
			(pintype "no_connect")
		)
		(pad "D9" smd circle
			(at 3.499 -5 180)
			(size 0.37 0.37)
			(layers "F.Cu" "F.Mask" "F.Paste")
			(net 471 "unconnected-(U1-VSF8-PadD9)")
			(pinfunction "VSF8")
			(pintype "no_connect")
		)
		(pad "E2" smd circle
			(at -3.5 -4 180)
			(size 0.37 0.37)
			(layers "F.Cu" "F.Mask" "F.Paste")
			(net 472 "unconnected-(U1-RFU-PadE2)")
			(pinfunction "RFU")
			(pintype "no_connect")
		)
		(pad "E3" smd circle
			(at -2.5 -4 180)
			(size 0.37 0.37)
			(layers "F.Cu" "F.Mask" "F.Paste")
			(net 473 "unconnected-(U1-RFU-PadE3)")
			(pinfunction "RFU")
			(pintype "no_connect")
		)
		(pad "E4" smd circle
			(at -1.5 -4 180)
			(size 0.37 0.37)
			(layers "F.Cu" "F.Mask" "F.Paste")
			(net 200 "Net-(U1-VDDIM)")
			(pinfunction "VDDIM")
			(pintype "power_in")
		)
		(pad "E5" smd circle
			(at -0.5 -4 180)
			(size 0.37 0.37)
			(layers "F.Cu" "F.Mask" "F.Paste")
			(net 480 "unconnected-(U1-RFU-PadE5)")
			(pinfunction "RFU")
			(pintype "no_connect")
		)
		(pad "E6" smd circle
			(at 0.499 -4 180)
			(size 0.37 0.37)
			(layers "F.Cu" "F.Mask" "F.Paste")
			(net 481 "unconnected-(U1-RFU-PadE6)")
			(pinfunction "RFU")
			(pintype "no_connect")
		)
		(pad "E7" smd circle
			(at 1.499 -4 180)
			(size 0.37 0.37)
			(layers "F.Cu" "F.Mask" "F.Paste")
			(net 482 "unconnected-(U1-RFU-PadE7)")
			(pinfunction "RFU")
			(pintype "no_connect")
		)
		(pad "E8" smd circle
			(at 2.499 -4 180)
			(size 0.37 0.37)
			(layers "F.Cu" "F.Mask" "F.Paste")
			(net 483 "unconnected-(U1-RFU-PadE8)")
			(pinfunction "RFU")
			(pintype "no_connect")
		)
		(pad "E9" smd circle
			(at 3.499 -4 180)
			(size 0.37 0.37)
			(layers "F.Cu" "F.Mask" "F.Paste")
			(net 484 "unconnected-(U1-RFU-PadE9)")
			(pinfunction "RFU")
			(pintype "no_connect")
		)
		(pad "F2" smd circle
			(at -3.5 -3 180)
			(size 0.37 0.37)
			(layers "F.Cu" "F.Mask" "F.Paste")
			(net 2 "VCC3V3")
			(pinfunction "VCC")
			(pintype "power_in")
		)
		(pad "F3" smd circle
			(at -2.5 -3 180)
			(size 0.37 0.37)
			(layers "F.Cu" "F.Mask" "F.Paste")
			(net 2 "VCC3V3")
			(pinfunction "VCC")
			(pintype "passive")
		)
		(pad "F4" smd circle
			(at -1.5 -3 180)
			(size 0.37 0.37)
			(layers "F.Cu" "F.Mask" "F.Paste")
			(net 2 "VCC3V3")
			(pinfunction "VCC")
			(pintype "passive")
		)
		(pad "F5" smd circle
			(at -0.5 -3 180)
			(size 0.37 0.37)
			(layers "F.Cu" "F.Mask" "F.Paste")
			(net 2 "VCC3V3")
			(pinfunction "VCC")
			(pintype "passive")
		)
		(pad "F6" smd circle
			(at 0.499 -3 180)
			(size 0.37 0.37)
			(layers "F.Cu" "F.Mask" "F.Paste")
			(net 2 "VCC3V3")
			(pinfunction "VCC")
			(pintype "passive")
		)
		(pad "F7" smd circle
			(at 1.499 -3 180)
			(size 0.37 0.37)
			(layers "F.Cu" "F.Mask" "F.Paste")
			(net 2 "VCC3V3")
			(pinfunction "VCC")
			(pintype "passive")
		)
		(pad "F8" smd circle
			(at 2.499 -3 180)
			(size 0.37 0.37)
			(layers "F.Cu" "F.Mask" "F.Paste")
			(net 2 "VCC3V3")
			(pinfunction "VCC")
			(pintype "passive")
		)
		(pad "F9" smd circle
			(at 3.499 -3 180)
			(size 0.37 0.37)
			(layers "F.Cu" "F.Mask" "F.Paste")
			(net 2 "VCC3V3")
			(pinfunction "VCC")
			(pintype "passive")
		)
		(pad "G2" smd circle
			(at -3.5 -2 180)
			(size 0.37 0.37)
			(layers "F.Cu" "F.Mask" "F.Paste")
			(net 1 "GND")
			(pinfunction "VSS")
			(pintype "power_in")
		)
		(pad "G3" smd circle
			(at -2.5 -2 180)
			(size 0.37 0.37)
			(layers "F.Cu" "F.Mask" "F.Paste")
			(net 1 "GND")
			(pinfunction "VSS")
			(pintype "passive")
		)
		(pad "G4" smd circle
			(at -1.5 -2 180)
			(size 0.37 0.37)
			(layers "F.Cu" "F.Mask" "F.Paste")
			(net 1 "GND")
			(pinfunction "VSS")
			(pintype "passive")
		)
		(pad "G5" smd circle
			(at -0.5 -2 180)
			(size 0.37 0.37)
			(layers "F.Cu" "F.Mask" "F.Paste")
			(net 1 "GND")
			(pinfunction "VSS")
			(pintype "passive")
		)
		(pad "G6" smd circle
			(at 0.499 -2 180)
			(size 0.37 0.37)
			(layers "F.Cu" "F.Mask" "F.Paste")
			(net 1 "GND")
			(pinfunction "VSS")
			(pintype "passive")
		)
		(pad "G7" smd circle
			(at 1.499 -2 180)
			(size 0.37 0.37)
			(layers "F.Cu" "F.Mask" "F.Paste")
			(net 1 "GND")
			(pinfunction "VSS")
			(pintype "passive")
		)
		(pad "G8" smd circle
			(at 2.499 -2 180)
			(size 0.37 0.37)
			(layers "F.Cu" "F.Mask" "F.Paste")
			(net 1 "GND")
			(pinfunction "VSS")
			(pintype "passive")
		)
		(pad "G9" smd circle
			(at 3.499 -2 180)
			(size 0.37 0.37)
			(layers "F.Cu" "F.Mask" "F.Paste")
			(net 1 "GND")
			(pinfunction "VSS")
			(pintype "passive")
		)
		(pad "H2" smd circle
			(at -3.5 -1 180)
			(size 0.37 0.37)
			(layers "F.Cu" "F.Mask" "F.Paste")
			(net 1 "GND")
			(pinfunction "VSSQ")
			(pintype "power_in")
		)
		(pad "H3" smd circle
			(at -2.5 -1 180)
			(size 0.37 0.37)
			(layers "F.Cu" "F.Mask" "F.Paste")
			(net 2 "VCC3V3")
			(pinfunction "VCCQ")
			(pintype "power_in")
		)
		(pad "H4" smd circle
			(at -1.5 -1 180)
			(size 0.37 0.37)
			(layers "F.Cu" "F.Mask" "F.Paste")
			(net 485 "unconnected-(U1-RFU-PadH4)")
			(pinfunction "RFU")
			(pintype "no_connect")
		)
		(pad "H5" smd circle
			(at -0.5 -1 180)
			(size 0.37 0.37)
			(layers "F.Cu" "F.Mask" "F.Paste")
			(net 486 "unconnected-(U1-RFU-PadH5)")
			(pinfunction "RFU")
			(pintype "no_connect")
		)
		(pad "H6" smd circle
			(at 0.499 -1 180)
			(size 0.37 0.37)
			(layers "F.Cu" "F.Mask" "F.Paste")
			(net 487 "unconnected-(U1-RFU-PadH6)")
			(pinfunction "RFU")
			(pintype "no_connect")
		)
		(pad "H7" smd circle
			(at 1.499 -1 180)
			(size 0.37 0.37)
			(layers "F.Cu" "F.Mask" "F.Paste")
			(net 488 "unconnected-(U1-RFU-PadH7)")
			(pinfunction "RFU")
			(pintype "no_connect")
		)
		(pad "H8" smd circle
			(at 2.499 -1 180)
			(size 0.37 0.37)
			(layers "F.Cu" "F.Mask" "F.Paste")
			(net 2 "VCC3V3")
			(pinfunction "VCCQ")
			(pintype "passive")
		)
		(pad "H9" smd circle
			(at 3.499 -1 180)
			(size 0.37 0.37)
			(layers "F.Cu" "F.Mask" "F.Paste")
			(net 1 "GND")
			(pinfunction "VSSQ")
			(pintype "passive")
		)
		(pad "J2" smd circle
			(at -3.5 0 180)
			(size 0.37 0.37)
			(layers "F.Cu" "F.Mask" "F.Paste")
			(net 491 "unconnected-(U1-RFU-PadJ2)")
			(pinfunction "RFU")
			(pintype "no_connect")
		)
		(pad "J3" smd circle
			(at -2.5 0 180)
			(size 0.37 0.37)
			(layers "F.Cu" "F.Mask" "F.Paste")
			(net 492 "unconnected-(U1-RFU-PadJ3)")
			(pinfunction "RFU")
			(pintype "no_connect")
		)
		(pad "J4" smd circle
			(at -1.5 0 180)
			(size 0.37 0.37)
			(layers "F.Cu" "F.Mask" "F.Paste")
			(net 493 "unconnected-(U1-RFU-PadJ4)")
			(pinfunction "RFU")
			(pintype "no_connect")
		)
		(pad "J5" smd circle
			(at -0.5 0 180)
			(size 0.37 0.37)
			(layers "F.Cu" "F.Mask" "F.Paste")
			(net 1 "GND")
			(pinfunction "VSS")
			(pintype "passive")
		)
		(pad "J6" smd circle
			(at 0.499 0 180)
			(size 0.37 0.37)
			(layers "F.Cu" "F.Mask" "F.Paste")
			(net 494 "unconnected-(U1-RFU-PadJ6)")
			(pinfunction "RFU")
			(pintype "no_connect")
		)
		(pad "J7" smd circle
			(at 1.499 0 180)
			(size 0.37 0.37)
			(layers "F.Cu" "F.Mask" "F.Paste")
			(net 495 "unconnected-(U1-RFU-PadJ7)")
			(pinfunction "RFU")
			(pintype "no_connect")
		)
		(pad "J8" smd circle
			(at 2.499 0 180)
			(size 0.37 0.37)
			(layers "F.Cu" "F.Mask" "F.Paste")
			(net 496 "unconnected-(U1-RFU-PadJ8)")
			(pinfunction "RFU")
			(pintype "no_connect")
		)
		(pad "J9" smd circle
			(at 3.499 0 180)
			(size 0.37 0.37)
			(layers "F.Cu" "F.Mask" "F.Paste")
			(net 497 "unconnected-(U1-RFU-PadJ9)")
			(pinfunction "RFU")
			(pintype "no_connect")
		)
		(pad "K2" smd circle
			(at -3.5 0.999 180)
			(size 0.37 0.37)
			(layers "F.Cu" "F.Mask" "F.Paste")
			(net 321 "MMC_DAT0")
			(pinfunction "DAT0")
			(pintype "bidirectional")
		)
		(pad "K3" smd circle
			(at -2.5 0.999 180)
			(size 0.37 0.37)
			(layers "F.Cu" "F.Mask" "F.Paste")
			(net 323 "MMC_DAT2")
			(pinfunction "DAT2")
			(pintype "bidirectional")
		)
		(pad "K4" smd circle
			(at -1.5 0.999 180)
			(size 0.37 0.37)
			(layers "F.Cu" "F.Mask" "F.Paste")
			(net 498 "unconnected-(U1-RFU-PadK4)")
			(pinfunction "RFU")
			(pintype "no_connect")
		)
		(pad "K5" smd circle
			(at -0.5 0.999 180)
			(size 0.37 0.37)
			(layers "F.Cu" "F.Mask" "F.Paste")
			(net 402 "Net-(U1-DS)")
			(pinfunction "DS")
			(pintype "output")
		)
		(pad "K6" smd circle
			(at 0.499 0.999 180)
			(size 0.37 0.37)
			(layers "F.Cu" "F.Mask" "F.Paste")
			(net 499 "unconnected-(U1-RFU-PadK6)")
			(pinfunction "RFU")
			(pintype "no_connect")
		)
		(pad "K7" smd circle
			(at 1.499 0.999 180)
			(size 0.37 0.37)
			(layers "F.Cu" "F.Mask" "F.Paste")
			(net 500 "unconnected-(U1-RFU-PadK7)")
			(pinfunction "RFU")
			(pintype "no_connect")
		)
		(pad "K8" smd circle
			(at 2.499 0.999 180)
			(size 0.37 0.37)
			(layers "F.Cu" "F.Mask" "F.Paste")
			(net 326 "MMC_DAT5")
			(pinfunction "DAT5")
			(pintype "bidirectional")
		)
		(pad "K9" smd circle
			(at 3.499 0.999 180)
			(size 0.37 0.37)
			(layers "F.Cu" "F.Mask" "F.Paste")
			(net 328 "MMC_DAT7")
			(pinfunction "DAT7")
			(pintype "bidirectional")
		)
		(pad "L2" smd circle
			(at -3.5 1.999 180)
			(size 0.37 0.37)
			(layers "F.Cu" "F.Mask" "F.Paste")
			(net 2 "VCC3V3")
			(pinfunction "VCCQ")
			(pintype "passive")
		)
		(pad "L3" smd circle
			(at -2.5 1.999 180)
			(size 0.37 0.37)
			(layers "F.Cu" "F.Mask" "F.Paste")
			(net 1 "GND")
			(pinfunction "VSSQ")
			(pintype "passive")
		)
		(pad "L4" smd circle
			(at -1.5 1.999 180)
			(size 0.37 0.37)
			(layers "F.Cu" "F.Mask" "F.Paste")
			(net 2 "VCC3V3")
			(pinfunction "VCCQ")
			(pintype "passive")
		)
		(pad "L5" smd circle
			(at -0.5 1.999 180)
			(size 0.37 0.37)
			(layers "F.Cu" "F.Mask" "F.Paste")
			(net 501 "unconnected-(U1-RFU-PadL5)")
			(pinfunction "RFU")
			(pintype "no_connect")
		)
		(pad "L6" smd circle
			(at 0.499 1.999 180)
			(size 0.37 0.37)
			(layers "F.Cu" "F.Mask" "F.Paste")
			(net 502 "unconnected-(U1-RFU-PadL6)")
			(pinfunction "RFU")
			(pintype "no_connect")
		)
		(pad "L7" smd circle
			(at 1.499 1.999 180)
			(size 0.37 0.37)
			(layers "F.Cu" "F.Mask" "F.Paste")
			(net 2 "VCC3V3")
			(pinfunction "VCCQ")
			(pintype "passive")
		)
		(pad "L8" smd circle
			(at 2.499 1.999 180)
			(size 0.37 0.37)
			(layers "F.Cu" "F.Mask" "F.Paste")
			(net 1 "GND")
			(pinfunction "VSSQ")
			(pintype "passive")
		)
		(pad "L9" smd circle
			(at 3.499 1.999 180)
			(size 0.37 0.37)
			(layers "F.Cu" "F.Mask" "F.Paste")
			(net 2 "VCC3V3")
			(pinfunction "VCCQ")
			(pintype "passive")
		)
		(pad "M2" smd circle
			(at -3.5 2.999 180)
			(size 0.37 0.37)
			(layers "F.Cu" "F.Mask" "F.Paste")
			(net 504 "unconnected-(U1-RFU-PadM2)")
			(pinfunction "RFU")
			(pintype "no_connect")
		)
		(pad "M3" smd circle
			(at -2.5 2.999 180)
			(size 0.37 0.37)
			(layers "F.Cu" "F.Mask" "F.Paste")
			(net 505 "unconnected-(U1-RFU-PadM3)")
			(pinfunction "RFU")
			(pintype "no_connect")
		)
		(pad "M4" smd circle
			(at -1.5 2.999 180)
			(size 0.37 0.37)
			(layers "F.Cu" "F.Mask" "F.Paste")
			(net 1 "GND")
			(pinfunction "VSSQ")
			(pintype "passive")
		)
		(pad "M5" smd circle
			(at -0.5 2.999 180)
			(size 0.37 0.37)
			(layers "F.Cu" "F.Mask" "F.Paste")
			(net 331 "MMC_RSTN")
			(pinfunction "RST_N")
			(pintype "input")
		)
		(pad "M6" smd circle
			(at 0.499 2.999 180)
			(size 0.37 0.37)
			(layers "F.Cu" "F.Mask" "F.Paste")
			(net 506 "unconnected-(U1-RFU-PadM6)")
			(pinfunction "RFU")
			(pintype "no_connect")
		)
		(pad "M7" smd circle
			(at 1.499 2.999 180)
			(size 0.37 0.37)
			(layers "F.Cu" "F.Mask" "F.Paste")
			(net 1 "GND")
			(pinfunction "VSSQ")
			(pintype "passive")
		)
		(pad "M8" smd circle
			(at 2.499 2.999 180)
			(size 0.37 0.37)
			(layers "F.Cu" "F.Mask" "F.Paste")
			(net 507 "unconnected-(U1-RFU-PadM8)")
			(pinfunction "RFU")
			(pintype "no_connect")
		)
		(pad "M9" smd circle
			(at 3.499 2.999 180)
			(size 0.37 0.37)
			(layers "F.Cu" "F.Mask" "F.Paste")
			(net 508 "unconnected-(U1-RFU-PadM9)")
			(pinfunction "RFU")
			(pintype "no_connect")
		)
		(pad "N2" smd circle
			(at -3.5 3.999 180)
			(size 0.37 0.37)
			(layers "F.Cu" "F.Mask" "F.Paste")
			(net 322 "MMC_DAT1")
			(pinfunction "DAT1")
			(pintype "bidirectional")
		)
		(pad "N3" smd circle
			(at -2.5 3.999 180)
			(size 0.37 0.37)
			(layers "F.Cu" "F.Mask" "F.Paste")
			(net 324 "MMC_DAT3")
			(pinfunction "DAT3")
			(pintype "bidirectional")
		)
		(pad "N4" smd circle
			(at -1.5 3.999 180)
			(size 0.37 0.37)
			(layers "F.Cu" "F.Mask" "F.Paste")
			(net 509 "unconnected-(U1-RFU-PadN4)")
			(pinfunction "RFU")
			(pintype "no_connect")
		)
		(pad "N5" smd circle
			(at -0.5 3.999 180)
			(size 0.37 0.37)
			(layers "F.Cu" "F.Mask" "F.Paste")
			(net 510 "unconnected-(U1-RFU-PadN5)")
			(pinfunction "RFU")
			(pintype "no_connect")
		)
		(pad "N6" smd circle
			(at 0.499 3.999 180)
			(size 0.37 0.37)
			(layers "F.Cu" "F.Mask" "F.Paste")
			(net 511 "unconnected-(U1-RFU-PadN6)")
			(pinfunction "RFU")
			(pintype "no_connect")
		)
		(pad "N7" smd circle
			(at 1.499 3.999 180)
			(size 0.37 0.37)
			(layers "F.Cu" "F.Mask" "F.Paste")
			(net 512 "unconnected-(U1-RFU-PadN7)")
			(pinfunction "RFU")
			(pintype "no_connect")
		)
		(pad "N8" smd circle
			(at 2.499 3.999 180)
			(size 0.37 0.37)
			(layers "F.Cu" "F.Mask" "F.Paste")
			(net 325 "MMC_DAT4")
			(pinfunction "DAT4")
			(pintype "bidirectional")
		)
	)
)
